(kicad_pcb
	(version 20260206)
	(generator "pcbnew")
	(generator_version "10.0")
	(general
		(thickness 1.6)
		(legacy_teardrops no)
	)
	(paper "A4")
	(title_block
		(title "Bryce Canyon_R.DPB_16317-1_OCP.brd")
		(comment 1 "Bryce Canyon / footprints 822-827 of 2099")
	)
	(layers
		(0 "F.Cu" signal "TOP")
		(4 "In1.Cu" signal "L2GND")
		(6 "In2.Cu" signal "L3")
		(8 "In3.Cu" signal "L4VCC")
		(10 "In4.Cu" signal "L5VCC")
		(12 "In5.Cu" signal "L6")
		(14 "In6.Cu" signal "L7GND")
		(2 "B.Cu" signal "BOTTOM")
		(9 "F.Adhes" user "F.Adhesive")
		(11 "B.Adhes" user "B.Adhesive")
		(13 "F.Paste" user "Package Geometry/Pastemask Top")
		(15 "B.Paste" user "Package Geometry/Pastemask Bottom")
		(5 "F.SilkS" user "Ref Des/Silkscreen Top")
		(7 "B.SilkS" user "Ref Des/Silkscreen Bottom")
		(1 "F.Mask" user "Board Geometry/Soldermask Top")
		(3 "B.Mask" user "Board Geometry/Soldermask Bottom")
		(17 "Dwgs.User" user "User.Drawings")
		(19 "Cmts.User" user "User.Comments")
		(21 "Eco1.User" user "User.Eco1")
		(23 "Eco2.User" user "User.Eco2")
		(25 "Edge.Cuts" user "Board Geometry/Outline")
		(27 "Margin" user)
		(31 "F.CrtYd" user "Package Geometry/Place Bound Top")
		(29 "B.CrtYd" user "Package Geometry/Place Bound Bottom")
		(35 "F.Fab" user "Ref Des/Assembly Top")
		(33 "B.Fab" user "Ref Des/Assembly Bottom")
	)
	(footprint ""
		(layer "F.Cu")
		(at 201.836274 -333.39659 90)
		(property "Reference" "Q195"
			(at 0 0 90)
			(layer "F.SilkS")
			(hide yes)
			(effects
				(font
					(size 1.27 1.27)
				)
			)
		)
		(property "Value" "IRFH8201TRPBF-GP"
			(at -4.2164 -4.3688 90)
			(unlocked yes)
			(layer "F.Fab")
			(hide yes)
			(effects
				(font
					(size 1.016 1.016)
					(thickness 0.1524)
				)
			)
		)
		(property "Device Type" "PPAK-5PH42"
			(at -4.2164 -5.8928 90)
			(unlocked yes)
			(layer "F.Fab")
			(hide yes)
			(effects
				(font
					(size 1.016 1.016)
					(thickness 0.1524)
				)
			)
		)
		(duplicate_pad_numbers_are_jumpers no)
		(fp_line
			(start 2.8956 -2.794)
			(end 2.8956 4.826)
			(stroke
				(width 0.1524)
				(type default)
			)
			(layer "F.SilkS")
		)
		(fp_line
			(start -2.8956 -2.794)
			(end 2.8956 -2.794)
			(stroke
				(width 0.1524)
				(type default)
			)
			(layer "F.SilkS")
		)
		(fp_line
			(start 2.8956 4.826)
			(end -2.8956 4.826)
			(stroke
				(width 0.1524)
				(type default)
			)
			(layer "F.SilkS")
		)
		(fp_line
			(start -2.8956 4.826)
			(end -2.8956 -2.794)
			(stroke
				(width 0.1524)
				(type default)
			)
			(layer "F.SilkS")
		)
		(fp_line
			(start -1.9431 4.9276)
			(end -3.0353 4.9276)
			(stroke
				(width 0.3302)
				(type default)
			)
			(layer "F.SilkS")
		)
		(fp_line
			(start -3.0353 4.9276)
			(end -3.0353 3.9624)
			(stroke
				(width 0.3302)
				(type default)
			)
			(layer "F.SilkS")
		)
		(fp_poly
			(pts
				(xy -2.3622 5.334) (xy -1.4986 5.334) (xy -1.9304 4.9022)
			)
			(stroke
				(width 0)
				(type default)
			)
			(fill yes)
			(layer "F.SilkS")
		)
		(fp_poly
			(pts
				(xy 0.3556 -0.3556) (xy 2.6416 -0.3556) (xy 2.6416 -2.54) (xy 0.3556 -2.54)
			)
			(stroke
				(width 0)
				(type default)
			)
			(fill yes)
			(layer "F.Paste")
		)
		(fp_poly
			(pts
				(xy -2.6416 -0.3556) (xy -0.3556 -0.3556) (xy -0.3556 -2.54) (xy -2.6416 -2.54)
			)
			(stroke
				(width 0)
				(type default)
			)
			(fill yes)
			(layer "F.Paste")
		)
		(fp_poly
			(pts
				(xy 0.3556 2.54) (xy 2.6416 2.54) (xy 2.6416 0.3556) (xy 0.3556 0.3556)
			)
			(stroke
				(width 0)
				(type default)
			)
			(fill yes)
			(layer "F.Paste")
		)
		(fp_poly
			(pts
				(xy -2.6416 2.54) (xy -0.3556 2.54) (xy -0.3556 0.3556) (xy -2.6416 0.3556)
			)
			(stroke
				(width 0)
				(type default)
			)
			(fill yes)
			(layer "F.Paste")
		)
		(fp_rect
			(start -2.5781 3.9878)
			(end 2.5781 -2.1082)
			(stroke
				(width 0)
				(type default)
			)
			(fill no)
			(layer "F.CrtYd")
		)
		(fp_poly
			(pts
				(xy -3.1496 5.08) (xy -3.1496 -3.048) (xy 3.1496 -3.048) (xy 3.1496 3.9751) (xy 2.5781 3.9751) (xy 2.5781 -2.1082)
				(xy -2.5781 -2.1082) (xy -2.5781 3.9878) (xy 3.1496 3.9878) (xy 3.1496 5.08)
			)
			(stroke
				(width 0)
				(type default)
			)
			(fill no)
			(layer "F.CrtYd")
		)
		(fp_rect
			(start -3.1496 5.08)
			(end 3.1496 -3.048)
			(stroke
				(width 0)
				(type default)
			)
			(fill no)
			(layer "F.Fab")
		)
		(pad "1" smd rect
			(at -1.905 3.81 90)
			(size 0.762 1.524)
			(layers "F.Cu" "F.Mask" "F.Paste")
			(net "P12V_IN")
		)
		(pad "2" smd rect
			(at -0.635 3.81 90)
			(size 0.762 1.524)
			(layers "F.Cu" "F.Mask" "F.Paste")
			(net "P12V_IN")
		)
		(pad "3" smd rect
			(at 0.635 3.81 90)
			(size 0.762 1.524)
			(layers "F.Cu" "F.Mask" "F.Paste")
			(net "P12V_IN")
		)
		(pad "4" smd rect
			(at 1.905 3.81 90)
			(size 0.762 1.524)
			(layers "F.Cu" "F.Mask" "F.Paste")
			(net "MB0_12V_CTRL_GATE2")
		)
		(pad "5" smd rect
			(at 0 0 90)
			(size 5.2832 5.08)
			(layers "F.Cu" "F.Mask" "F.Paste")
			(net "MB0_P12V_IN_R")
		)
		(pad "6" smd rect
			(at 0.635 -2.032 90)
			(size 0.0254 0.0254)
			(layers "F.Cu" "F.Mask" "F.Paste")
			(net "MB0_P12V_IN_R")
		)
		(pad "7" smd rect
			(at -0.635 -2.032 90)
			(size 0.0254 0.0254)
			(layers "F.Cu" "F.Mask" "F.Paste")
			(net "MB0_P12V_IN_R")
		)
		(pad "8" smd rect
			(at -1.905 -2.032 90)
			(size 0.0254 0.0254)
			(layers "F.Cu" "F.Mask" "F.Paste")
			(net "MB0_P12V_IN_R")
		)
	)
	(footprint ""
		(layer "F.Cu")
		(at 409.800044 -65.39992)
		(property "Reference" "LED22"
			(at 0 0 0)
			(layer "F.SilkS")
			(hide yes)
			(effects
				(font
					(size 1.27 1.27)
				)
			)
		)
		(property "Value" "LED-BY-19-GP"
			(at -2.132076 1.414018 0)
			(unlocked yes)
			(layer "F.Fab")
			(hide yes)
			(effects
				(font
					(size 1.016 1.016)
					(thickness 0.1524)
				)
			)
		)
		(property "Device Type" "LED-1615-4PH26"
			(at -2.132076 -0.109982 0)
			(unlocked yes)
			(layer "F.Fab")
			(hide yes)
			(effects
				(font
					(size 1.016 1.016)
					(thickness 0.1524)
				)
			)
		)
		(duplicate_pad_numbers_are_jumpers no)
		(fp_line
			(start -1.2954 0.254)
			(end -1.2954 1.6002)
			(stroke
				(width 0.508)
				(type default)
			)
			(layer "F.SilkS")
		)
		(fp_line
			(start -1.2954 1.6002)
			(end 1.2954 1.6002)
			(stroke
				(width 0.508)
				(type default)
			)
			(layer "F.SilkS")
		)
		(fp_line
			(start -1.1176 -1.4224)
			(end 1.1176 -1.4224)
			(stroke
				(width 0.1524)
				(type default)
			)
			(layer "F.SilkS")
		)
		(fp_line
			(start -1.1176 1.4224)
			(end -1.1176 -1.4224)
			(stroke
				(width 0.1524)
				(type default)
			)
			(layer "F.SilkS")
		)
		(fp_line
			(start 1.1176 -1.4224)
			(end 1.1176 1.4224)
			(stroke
				(width 0.1524)
				(type default)
			)
			(layer "F.SilkS")
		)
		(fp_line
			(start 1.1176 1.4224)
			(end -1.1176 1.4224)
			(stroke
				(width 0.1524)
				(type default)
			)
			(layer "F.SilkS")
		)
		(fp_line
			(start 1.2954 1.6002)
			(end 1.2954 0.254)
			(stroke
				(width 0.508)
				(type default)
			)
			(layer "F.SilkS")
		)
		(fp_rect
			(start -0.7493 0.8001)
			(end 0.7493 -0.8001)
			(stroke
				(width 0)
				(type default)
			)
			(fill no)
			(layer "F.CrtYd")
		)
		(fp_poly
			(pts
				(xy -1.3716 1.6764) (xy -1.3716 -1.6764) (xy 1.3716 -1.6764) (xy 1.3716 0.0635) (xy 0.7493 0.0635)
				(xy 0.7493 -0.8001) (xy -0.7493 -0.8001) (xy -0.7493 0.8001) (xy 0.7493 0.8001) (xy 0.7493 0.0762)
				(xy 1.3716 0.0762) (xy 1.3716 1.6764)
			)
			(stroke
				(width 0)
				(type default)
			)
			(fill no)
			(layer "F.CrtYd")
		)
		(fp_rect
			(start -1.3716 1.6764)
			(end 1.3716 -1.6764)
			(stroke
				(width 0)
				(type default)
			)
			(fill no)
			(layer "F.Fab")
		)
		(pad "1" smd rect
			(at 0.50038 -0.73025)
			(size 0.7112 0.8636)
			(layers "F.Cu" "F.Mask" "F.Paste")
			(net "DRV_ACT_21")
		)
		(pad "2" smd rect
			(at -0.50038 -0.73025)
			(size 0.7112 0.8636)
			(layers "F.Cu" "F.Mask" "F.Paste")
			(net "FLT_HDD21")
		)
		(pad "3" smd rect
			(at 0.50038 0.73025)
			(size 0.7112 0.8636)
			(layers "F.Cu" "F.Mask" "F.Paste")
			(net "DRV_ACT_21_N")
		)
		(pad "4" smd rect
			(at -0.50038 0.73025)
			(size 0.7112 0.8636)
			(layers "F.Cu" "F.Mask" "F.Paste")
			(net "FLT_HDD21_N")
		)
	)
	(footprint ""
		(layer "F.Cu")
		(at 367.284 -16.764 180)
		(property "Reference" "R800"
			(at 0 0 180)
			(layer "F.SilkS")
			(hide yes)
			(effects
				(font
					(size 1.27 1.27)
				)
			)
		)
		(property "Value" "0R2J-2-GP"
			(at 0.064008 -3.993896 180)
			(unlocked yes)
			(layer "F.Fab")
			(hide yes)
			(effects
				(font
					(size 1.016 1.016)
					(thickness 0.1524)
				)
			)
		)
		(property "Device Type" "R402H16"
			(at 0.064008 -5.517896 180)
			(unlocked yes)
			(layer "F.Fab")
			(hide yes)
			(effects
				(font
					(size 1.016 1.016)
					(thickness 0.1524)
				)
			)
		)
		(duplicate_pad_numbers_are_jumpers no)
		(fp_line
			(start 0.508 -0.9398)
			(end -0.508 -0.9398)
			(stroke
				(width 0.1524)
				(type default)
			)
			(layer "F.SilkS")
		)
		(fp_line
			(start -0.508 -0.9398)
			(end -0.508 0.9398)
			(stroke
				(width 0.1524)
				(type default)
			)
			(layer "F.SilkS")
		)
		(fp_rect
			(start -0.508 0.9398)
			(end 0.508 -0.9398)
			(stroke
				(width 0)
				(type default)
			)
			(fill no)
			(layer "F.CrtYd")
		)
		(fp_rect
			(start -0.508 0.9398)
			(end 0.508 -0.9398)
			(stroke
				(width 0)
				(type default)
			)
			(fill no)
			(layer "F.Fab")
		)
		(pad "1" smd custom
			(at 0 -0.4445 180)
			(size 0.1397 0.1397)
			(layers "F.Cu" "F.Mask" "F.Paste")
			(net "SW_HDD_G31")
			(options
				(clearance outline)
				(anchor circle)
			)
			(primitives
				(gr_poly
					(pts
						(arc
							(start -0.1778 -0.2794)
							(mid -0.249642 -0.249642)
							(end -0.2794 -0.1778)
						)
						(arc
							(start -0.2794 0.1778)
							(mid -0.249642 0.249642)
							(end -0.1778 0.2794)
						)
						(arc
							(start 0.1778 0.2794)
							(mid 0.249642 0.249642)
							(end 0.2794 0.1778)
						)
						(arc
							(start 0.2794 -0.1778)
							(mid 0.249642 -0.249642)
							(end 0.1778 -0.2794)
						)
					)
					(width 0)
					(fill yes)
				)
			)
		)
		(pad "2" smd custom
			(at 0 0.4445 180)
			(size 0.1397 0.1397)
			(layers "F.Cu" "F.Mask" "F.Paste")
			(net "SW_HDD_R31")
			(options
				(clearance outline)
				(anchor circle)
			)
			(primitives
				(gr_poly
					(pts
						(arc
							(start -0.1778 -0.2794)
							(mid -0.249642 -0.249642)
							(end -0.2794 -0.1778)
						)
						(arc
							(start -0.2794 0.1778)
							(mid -0.249642 0.249642)
							(end -0.1778 0.2794)
						)
						(arc
							(start 0.1778 0.2794)
							(mid 0.249642 0.249642)
							(end 0.2794 0.1778)
						)
						(arc
							(start 0.2794 -0.1778)
							(mid 0.249642 -0.249642)
							(end 0.1778 -0.2794)
						)
					)
					(width 0)
					(fill yes)
				)
			)
		)
	)
	(footprint ""
		(layer "F.Cu")
		(at 311.904126 -214.757 180)
		(property "Reference" "Q225"
			(at 0 0 180)
			(layer "F.SilkS")
			(hide yes)
			(effects
				(font
					(size 1.27 1.27)
				)
			)
		)
		(property "Value" "2N7002K-2-GP"
			(at 0.127 -8.9662 180)
			(unlocked yes)
			(layer "F.Fab")
			(hide yes)
			(effects
				(font
					(size 1.016 1.016)
					(thickness 0.1524)
				)
			)
		)
		(property "Device Type" "SOT23DGS2D4H44"
			(at 0.127 -10.4902 180)
			(unlocked yes)
			(layer "F.Fab")
			(hide yes)
			(effects
				(font
					(size 1.016 1.016)
					(thickness 0.1524)
				)
			)
		)
		(duplicate_pad_numbers_are_jumpers no)
		(fp_line
			(start 1.651 1.778)
			(end 1.651 -1.778)
			(stroke
				(width 0.1524)
				(type default)
			)
			(layer "F.SilkS")
		)
		(fp_line
			(start 1.651 -1.778)
			(end -1.651 -1.778)
			(stroke
				(width 0.1524)
				(type default)
			)
			(layer "F.SilkS")
		)
		(fp_line
			(start -1.651 1.778)
			(end 1.651 1.778)
			(stroke
				(width 0.1524)
				(type default)
			)
			(layer "F.SilkS")
		)
		(fp_line
			(start -1.651 -1.778)
			(end -1.651 1.778)
			(stroke
				(width 0.1524)
				(type default)
			)
			(layer "F.SilkS")
		)
		(fp_poly
			(pts
				(xy -1.778 1.8796) (xy -1.778 -1.8796) (xy 1.778 -1.8796) (xy 1.778 1.8796)
			)
			(stroke
				(width 0)
				(type default)
			)
			(fill no)
			(layer "F.CrtYd")
		)
		(fp_poly
			(pts
				(xy -1.778 1.8796) (xy -1.778 -1.8796) (xy 1.778 -1.8796) (xy 1.778 1.8796)
			)
			(stroke
				(width 0)
				(type default)
			)
			(fill no)
			(layer "F.Fab")
		)
		(pad "D" smd custom
			(at 0 -0.9525 180)
			(size 0.1905 0.1905)
			(layers "F.Cu" "F.Mask" "F.Paste")
			(net "FLT_HDD6_N")
			(options
				(clearance outline)
				(anchor circle)
			)
			(primitives
				(gr_poly
					(pts
						(arc
							(start -0.1778 0.5715)
							(mid -0.321484 0.511984)
							(end -0.381 0.3683)
						)
						(arc
							(start -0.381 -0.3683)
							(mid -0.321484 -0.511984)
							(end -0.1778 -0.5715)
						)
						(arc
							(start 0.1778 -0.5715)
							(mid 0.321484 -0.511984)
							(end 0.381 -0.3683)
						)
						(arc
							(start 0.381 0.3683)
							(mid 0.321484 0.511984)
							(end 0.1778 0.5715)
						)
					)
					(width 0)
					(fill yes)
				)
			)
		)
		(pad "G" smd custom
			(at -0.98425 0.9525 180)
			(size 0.1905 0.1905)
			(layers "F.Cu" "F.Mask" "F.Paste")
			(net "DRIVE_B_6_FLT_LED")
			(options
				(clearance outline)
				(anchor circle)
			)
			(primitives
				(gr_poly
					(pts
						(arc
							(start -0.1778 0.5715)
							(mid -0.321484 0.511984)
							(end -0.381 0.3683)
						)
						(arc
							(start -0.381 -0.3683)
							(mid -0.321484 -0.511984)
							(end -0.1778 -0.5715)
						)
						(arc
							(start 0.1778 -0.5715)
							(mid 0.321484 -0.511984)
							(end 0.381 -0.3683)
						)
						(arc
							(start 0.381 0.3683)
							(mid 0.321484 0.511984)
							(end 0.1778 0.5715)
						)
					)
					(width 0)
					(fill yes)
				)
			)
		)
		(pad "S" smd custom
			(at 0.98425 0.9525 180)
			(size 0.1905 0.1905)
			(layers "F.Cu" "F.Mask" "F.Paste")
			(net "GND")
			(options
				(clearance outline)
				(anchor circle)
			)
			(primitives
				(gr_poly
					(pts
						(arc
							(start -0.1778 0.5715)
							(mid -0.321484 0.511984)
							(end -0.381 0.3683)
						)
						(arc
							(start -0.381 -0.3683)
							(mid -0.321484 -0.511984)
							(end -0.1778 -0.5715)
						)
						(arc
							(start 0.1778 -0.5715)
							(mid 0.321484 -0.511984)
							(end 0.381 -0.3683)
						)
						(arc
							(start 0.381 0.3683)
							(mid 0.321484 0.511984)
							(end 0.1778 0.5715)
						)
					)
					(width 0)
					(fill yes)
				)
			)
		)
	)
	(footprint ""
		(layer "F.Cu")
		(at 323.3166 -17.4371)
		(property "Reference" "VIA62"
			(at 0 0 0)
			(layer "F.SilkS")
			(hide yes)
			(effects
				(font
					(size 1.27 1.27)
				)
			)
		)
		(property "Value" "100OHM-8L-2D36MM-L16-GP"
			(at -3.4036 -0.4572 0)
			(unlocked yes)
			(layer "F.Fab")
			(hide yes)
			(effects
				(font
					(size 1.016 1.016)
					(thickness 0.1524)
				)
			)
		)
		(property "Device Type" "VIA-PCIE-4P-427097"
			(at -3.4036 -1.9812 0)
			(unlocked yes)
			(layer "F.Fab")
			(hide yes)
			(effects
				(font
					(size 1.016 1.016)
					(thickness 0.1524)
				)
			)
		)
		(duplicate_pad_numbers_are_jumpers no)
		(fp_rect
			(start -2.1336 0.4826)
			(end 2.1336 -0.4826)
			(stroke
				(width 0)
				(type default)
			)
			(fill no)
			(layer "F.CrtYd")
		)
		(fp_rect
			(start -2.1336 0.4826)
			(end 2.1336 -0.4826)
			(stroke
				(width 0)
				(type default)
			)
			(fill no)
			(layer "F.Fab")
		)
		(pad "1" thru_hole circle
			(at -1.651 0)
			(size 0.508 0.508)
			(drill 0.254)
			(layers "*.Cu" "*.Mask")
			(remove_unused_layers no)
			(net "GND")
			(clearance 0.2286)
			(thermal_gap 0.2286)
		)
		(pad "2" thru_hole circle
			(at -0.635 0)
			(size 0.508 0.508)
			(drill 0.254)
			(layers "*.Cu" "*.Mask")
			(remove_unused_layers no)
			(net "PHY_DRV_B_TO_SCC_B_30_DP")
			(clearance 0.2286)
			(thermal_gap 0.2286)
		)
		(pad "3" thru_hole circle
			(at 0.635 0)
			(size 0.508 0.508)
			(drill 0.254)
			(layers "*.Cu" "*.Mask")
			(remove_unused_layers no)
			(net "PHY_DRV_B_TO_SCC_B_30_DN")
			(clearance 0.2286)
			(thermal_gap 0.2286)
		)
		(pad "4" thru_hole circle
			(at 1.651 0)
			(size 0.508 0.508)
			(drill 0.254)
			(layers "*.Cu" "*.Mask")
			(remove_unused_layers no)
			(net "GND")
			(clearance 0.2286)
			(thermal_gap 0.2286)
		)
	)
	(footprint ""
		(layer "F.Cu")
		(at 335.153 -360.299)
		(property "Reference" "R968"
			(at 0 0 0)
			(layer "F.SilkS")
			(hide yes)
			(effects
				(font
					(size 1.27 1.27)
				)
			)
		)
		(property "Value" "4K7R2J-2-GP"
			(at 0.064008 -3.993896 0)
			(unlocked yes)
			(layer "F.Fab")
			(hide yes)
			(effects
				(font
					(size 1.016 1.016)
					(thickness 0.1524)
				)
			)
		)
		(property "Device Type" "R402H16"
			(at 0.064008 -5.517896 0)
			(unlocked yes)
			(layer "F.Fab")
			(hide yes)
			(effects
				(font
					(size 1.016 1.016)
					(thickness 0.1524)
				)
			)
		)
		(duplicate_pad_numbers_are_jumpers no)
		(fp_line
			(start -0.508 -0.9398)
			(end -0.508 0.9398)
			(stroke
				(width 0.1524)
				(type default)
			)
			(layer "F.SilkS")
		)
		(fp_line
			(start 0.508 -0.9398)
			(end -0.508 -0.9398)
			(stroke
				(width 0.1524)
				(type default)
			)
			(layer "F.SilkS")
		)
		(fp_rect
			(start -0.508 0.9398)
			(end 0.508 -0.9398)
			(stroke
				(width 0)
				(type default)
			)
			(fill no)
			(layer "F.CrtYd")
		)
		(fp_rect
			(start -0.508 0.9398)
			(end 0.508 -0.9398)
			(stroke
				(width 0)
				(type default)
			)
			(fill no)
			(layer "F.Fab")
		)
		(pad "1" smd custom
			(at 0 -0.4445)
			(size 0.1397 0.1397)
			(layers "F.Cu" "F.Mask" "F.Paste")
			(net "P12V_IN")
			(options
				(clearance outline)
				(anchor circle)
			)
			(primitives
				(gr_poly
					(pts
						(arc
							(start -0.1778 -0.2794)
							(mid -0.249642 -0.249642)
							(end -0.2794 -0.1778)
						)
						(arc
							(start -0.2794 0.1778)
							(mid -0.249642 0.249642)
							(end -0.1778 0.2794)
						)
						(arc
							(start 0.1778 0.2794)
							(mid 0.249642 0.249642)
							(end 0.2794 0.1778)
						)
						(arc
							(start 0.2794 -0.1778)
							(mid 0.249642 -0.249642)
							(end 0.1778 -0.2794)
						)
					)
					(width 0)
					(fill yes)
				)
			)
		)
		(pad "2" smd custom
			(at 0 0.4445)
			(size 0.1397 0.1397)
			(layers "F.Cu" "F.Mask" "F.Paste")
			(net "GATE_FAN2")
			(options
				(clearance outline)
				(anchor circle)
			)
			(primitives
				(gr_poly
					(pts
						(arc
							(start -0.1778 -0.2794)
							(mid -0.249642 -0.249642)
							(end -0.2794 -0.1778)
						)
						(arc
							(start -0.2794 0.1778)
							(mid -0.249642 0.249642)
							(end -0.1778 0.2794)
						)
						(arc
							(start 0.1778 0.2794)
							(mid 0.249642 0.249642)
							(end 0.2794 0.1778)
						)
						(arc
							(start 0.2794 -0.1778)
							(mid 0.249642 -0.249642)
							(end 0.1778 -0.2794)
						)
					)
					(width 0)
					(fill yes)
				)
			)
		)
	)
)
